# BASEBOARD_FAB2 (Tioga Pass) — schematic netlist excerpt (pin names and nets, part order shuffled) for the footprints in the layout excerpt that follows; sources: Cadence DE-HDL packaged netlist, KiCad conversion of Wiwynn_Tioga_Pass_MB.brd

C843  CAP  0.22UF 16V 10% X7R  pkg 0402  page 244 : A = P3E_CPU0_PE1_PCH_TXP<8> ; B = P3E_CPU0_PE1_PCH_CON_TXP<8>
RF11  RES  1.0K 0.1% CHIP  pkg 0402  page 206 : A = VR_PVCCIN_CPU1_AIREF5 ; B = ISENSE_PVCCIN_CPU1_PH5_IMON
R1D39  RES  100.0K 1% CHIP  pkg 0402  page 199 : A = A_HSC_VCAP ; B = A_HSC_PSET

(kicad_pcb
	(version 20260206)
	(generator "pcbnew")
	(generator_version "10.0")
	(general
		(thickness 1.6)
		(legacy_teardrops no)
	)
	(paper "A4")
	(title_block
		(title "Wiwynn_Tioga_Pass_MB.brd")
		(comment 1 "Tioga Pass / footprints 520-522 of 4770")
	)
	(layers
		(0 "F.Cu" signal "TOP")
		(4 "In1.Cu" signal "L2GND")
		(6 "In2.Cu" signal "L3")
		(8 "In3.Cu" signal "L4GND")
		(10 "In4.Cu" signal "L5")
		(12 "In5.Cu" signal "L6GND")
		(14 "In6.Cu" signal "L7VCC")
		(16 "In7.Cu" signal "L8VCC")
		(18 "In8.Cu" signal "L9GND")
		(20 "In9.Cu" signal "L10")
		(22 "In10.Cu" signal "L11GND")
		(24 "In11.Cu" signal "L12")
		(26 "In12.Cu" signal "L13GND")
		(2 "B.Cu" signal "BOTTOM")
		(9 "F.Adhes" user "F.Adhesive")
		(11 "B.Adhes" user "B.Adhesive")
		(13 "F.Paste" user "Package Geometry/Pastemask Top")
		(15 "B.Paste" user "Package Geometry/Pastemask Bottom")
		(5 "F.SilkS" user "Ref Des/Silkscreen Top")
		(7 "B.SilkS" user "Ref Des/Silkscreen Bottom")
		(1 "F.Mask" user "Board Geometry/Soldermask Top")
		(3 "B.Mask" user "Board Geometry/Soldermask Bottom")
		(17 "Dwgs.User" user "User.Drawings")
		(19 "Cmts.User" user "User.Comments")
		(21 "Eco1.User" user "User.Eco1")
		(23 "Eco2.User" user "User.Eco2")
		(25 "Edge.Cuts" user "Board Geometry/Outline")
		(27 "Margin" user)
		(31 "F.CrtYd" user "Package Geometry/Place Bound Top")
		(29 "B.CrtYd" user "Package Geometry/Place Bound Bottom")
		(35 "F.Fab" user "Ref Des/Assembly Top")
		(33 "B.Fab" user "Ref Des/Assembly Bottom")
	)
	(footprint ""
		(layer "F.Cu")
		(at 24.05634 -93.323156 180)
		(property "Reference" "RF11"
			(at -0.8382 -0.67818 180)
			(unlocked yes)
			(layer "F.SilkS")
			(effects
				(font
					(size 0.4064 0.254)
					(thickness 0.1524)
				)
				(justify left)
			)
		)
		(property "Value" ""
			(at 0 0 180)
			(layer "F.Fab")
			(effects
				(font
					(size 1.27 1.27)
				)
			)
		)
		(duplicate_pad_numbers_are_jumpers no)
		(fp_poly
			(pts
				(xy -0.2794 -0.1016) (xy 0.2794 -0.1016) (xy 0.2794 0.9906) (xy -0.2794 0.9906)
			)
			(stroke
				(width 0)
				(type default)
			)
			(fill no)
			(layer "F.CrtYd")
		)
		(fp_line
			(start 0.2794 0.9906)
			(end 0.2794 -0.1016)
			(stroke
				(width 0.1)
				(type default)
			)
			(layer "F.Fab")
		)
		(fp_line
			(start 0.2794 -0.1016)
			(end -0.2794 -0.1016)
			(stroke
				(width 0.1)
				(type default)
			)
			(layer "F.Fab")
		)
		(fp_line
			(start -0.2794 0.9906)
			(end 0.2794 0.9906)
			(stroke
				(width 0.1)
				(type default)
			)
			(layer "F.Fab")
		)
		(fp_line
			(start -0.2794 -0.1016)
			(end -0.2794 0.9906)
			(stroke
				(width 0.1)
				(type default)
			)
			(layer "F.Fab")
		)
		(pad "1" smd rect
			(at 0 0 180)
			(size 0.508 0.508)
			(layers "F.Cu" "F.Mask" "F.Paste")
			(net "VR_PVCCIN_CPU1_AIREF5")
		)
		(pad "2" smd rect
			(at 0 0.889 180)
			(size 0.508 0.508)
			(layers "F.Cu" "F.Mask" "F.Paste")
			(net "ISENSE_PVCCIN_CPU1_PH5_IMON")
		)
		(zone
			(layer "F.Cu")
			(hatch none 0.5)
			(connect_pads
				(clearance 0)
			)
			(min_thickness 0.25)
			(keepout
				(tracks not_allowed)
				(vias allowed)
				(pads allowed)
				(copperpour not_allowed)
				(footprints allowed)
			)
			(placement
				(enabled no)
				(sheetname "")
			)
			(fill
				(thermal_gap 0.5)
				(thermal_bridge_width 0.5)
				(island_removal_mode 0)
			)
			(polygon
				(pts
					(xy 24.31034 -93.958156) (xy 23.80234 -93.958156) (xy 23.80234 -93.577156) (xy 24.31034 -93.577156)
				)
			)
		)
		(zone
			(layer "F.Cu")
			(hatch none 0.5)
			(connect_pads
				(clearance 0)
			)
			(min_thickness 0.25)
			(keepout
				(tracks allowed)
				(vias not_allowed)
				(pads allowed)
				(copperpour not_allowed)
				(footprints allowed)
			)
			(placement
				(enabled no)
				(sheetname "")
			)
			(fill
				(thermal_gap 0.5)
				(thermal_bridge_width 0.5)
				(island_removal_mode 0)
			)
			(polygon
				(pts
					(xy 24.31034 -93.577156) (xy 23.80234 -93.577156) (xy 23.80234 -93.958156) (xy 24.31034 -93.958156)
				)
			)
		)
	)
	(footprint ""
		(layer "F.Cu")
		(at 23.114 -73.406 -90)
		(property "Reference" "R1D39"
			(at 0 0 270)
			(layer "F.SilkS")
			(hide yes)
			(effects
				(font
					(size 1.27 1.27)
				)
			)
		)
		(property "Value" ""
			(at 0 0 270)
			(layer "F.Fab")
			(effects
				(font
					(size 1.27 1.27)
				)
			)
		)
		(duplicate_pad_numbers_are_jumpers no)
		(fp_poly
			(pts
				(xy -0.2794 -0.1016) (xy 0.2794 -0.1016) (xy 0.2794 0.9906) (xy -0.2794 0.9906)
			)
			(stroke
				(width 0)
				(type default)
			)
			(fill no)
			(layer "F.CrtYd")
		)
		(fp_line
			(start -0.2794 0.9906)
			(end 0.2794 0.9906)
			(stroke
				(width 0.1)
				(type default)
			)
			(layer "F.Fab")
		)
		(fp_line
			(start 0.2794 0.9906)
			(end 0.2794 -0.1016)
			(stroke
				(width 0.1)
				(type default)
			)
			(layer "F.Fab")
		)
		(fp_line
			(start -0.2794 -0.1016)
			(end -0.2794 0.9906)
			(stroke
				(width 0.1)
				(type default)
			)
			(layer "F.Fab")
		)
		(fp_line
			(start 0.2794 -0.1016)
			(end -0.2794 -0.1016)
			(stroke
				(width 0.1)
				(type default)
			)
			(layer "F.Fab")
		)
		(pad "1" smd rect
			(at 0 0 270)
			(size 0.508 0.508)
			(layers "F.Cu" "F.Mask" "F.Paste")
			(net "A_HSC_VCAP")
		)
		(pad "2" smd rect
			(at 0 0.889 270)
			(size 0.508 0.508)
			(layers "F.Cu" "F.Mask" "F.Paste")
			(net "A_HSC_PSET")
		)
		(zone
			(layer "F.Cu")
			(hatch none 0.5)
			(connect_pads
				(clearance 0)
			)
			(min_thickness 0.25)
			(keepout
				(tracks not_allowed)
				(vias allowed)
				(pads allowed)
				(copperpour not_allowed)
				(footprints allowed)
			)
			(placement
				(enabled no)
				(sheetname "")
			)
			(fill
				(thermal_gap 0.5)
				(thermal_bridge_width 0.5)
				(island_removal_mode 0)
			)
			(polygon
				(pts
					(xy 22.479 -73.66) (xy 22.479 -73.152) (xy 22.86 -73.152) (xy 22.86 -73.66)
				)
			)
		)
		(zone
			(layer "F.Cu")
			(hatch none 0.5)
			(connect_pads
				(clearance 0)
			)
			(min_thickness 0.25)
			(keepout
				(tracks allowed)
				(vias not_allowed)
				(pads allowed)
				(copperpour not_allowed)
				(footprints allowed)
			)
			(placement
				(enabled no)
				(sheetname "")
			)
			(fill
				(thermal_gap 0.5)
				(thermal_bridge_width 0.5)
				(island_removal_mode 0)
			)
			(polygon
				(pts
					(xy 22.86 -73.66) (xy 22.86 -73.152) (xy 22.479 -73.152) (xy 22.479 -73.66)
				)
			)
		)
	)
	(footprint ""
		(layer "F.Cu")
		(at 332.888844 -117.35562 -90)
		(property "Reference" "C843"
			(at -0.8382 -0.67818 270)
			(unlocked yes)
			(layer "F.SilkS")
			(effects
				(font
					(size 0.4064 0.254)
					(thickness 0.1524)
				)
				(justify left)
			)
		)
		(property "Value" ""
			(at 0 0 270)
			(layer "F.Fab")
			(effects
				(font
					(size 1.27 1.27)
				)
			)
		)
		(duplicate_pad_numbers_are_jumpers no)
		(fp_poly
			(pts
				(xy 0.3048 -0.1016) (xy 0.3048 0.9906) (xy -0.3048 0.9906) (xy -0.3048 -0.1016)
			)
			(stroke
				(width 0)
				(type default)
			)
			(fill no)
			(layer "F.CrtYd")
		)
		(fp_line
			(start -0.3048 0.9906)
			(end 0.3048 0.9906)
			(stroke
				(width 0.1)
				(type default)
			)
			(layer "F.Fab")
		)
		(fp_line
			(start 0.3048 0.9906)
			(end 0.3048 -0.1016)
			(stroke
				(width 0.1)
				(type default)
			)
			(layer "F.Fab")
		)
		(fp_line
			(start -0.3048 -0.1016)
			(end -0.3048 0.9906)
			(stroke
				(width 0.1)
				(type default)
			)
			(layer "F.Fab")
		)
		(fp_line
			(start 0.3048 -0.1016)
			(end -0.3048 -0.1016)
			(stroke
				(width 0.1)
				(type default)
			)
			(layer "F.Fab")
		)
		(pad "1" smd rect
			(at 0 0 270)
			(size 0.508 0.508)
			(layers "F.Cu" "F.Mask" "F.Paste")
			(net "P3E_CPU0_PE1_PCH_TXP<8>")
		)
		(pad "2" smd rect
			(at 0 0.889 270)
			(size 0.508 0.508)
			(layers "F.Cu" "F.Mask" "F.Paste")
			(net "P3E_CPU0_PE1_PCH_CON_TXP<8>")
		)
		(zone
			(layer "F.Cu")
			(hatch none 0.5)
			(connect_pads
				(clearance 0)
			)
			(min_thickness 0.25)
			(keepout
				(tracks not_allowed)
				(vias allowed)
				(pads allowed)
				(copperpour not_allowed)
				(footprints allowed)
			)
			(placement
				(enabled no)
				(sheetname "")
			)
			(fill
				(thermal_gap 0.5)
				(thermal_bridge_width 0.5)
				(island_removal_mode 0)
			)
			(polygon
				(pts
					(xy 332.253844 -117.60962) (xy 332.253844 -117.10162) (xy 332.634844 -117.10162) (xy 332.634844 -117.60962)
				)
			)
		)
		(zone
			(layer "F.Cu")
			(hatch none 0.5)
			(connect_pads
				(clearance 0)
			)
			(min_thickness 0.25)
			(keepout
				(tracks allowed)
				(vias not_allowed)
				(pads allowed)
				(copperpour not_allowed)
				(footprints allowed)
			)
			(placement
				(enabled no)
				(sheetname "")
			)
			(fill
				(thermal_gap 0.5)
				(thermal_bridge_width 0.5)
				(island_removal_mode 0)
			)
			(polygon
				(pts
					(xy 332.634844 -117.60962) (xy 332.634844 -117.10162) (xy 332.253844 -117.10162) (xy 332.253844 -117.60962)
				)
			)
		)
	)
)
